(kicad_pcb
	(version 20260206)
	(generator "pcbnew")
	(generator_version "10.0")
	(general
		(thickness 1.59074)
		(legacy_teardrops no)
	)
	(paper "A4")
	(title_block
		(title "osc-sa45 — FAB_SA45_DaughterCard.PcbDoc")
		(comment 1 "Time Appliance Project (Time Card) / footprints 1-6 of 44")
	)
	(layers
		(0 "F.Cu" signal "L01-Top Layer")
		(4 "In1.Cu" signal "L02-Inner Layer")
		(6 "In2.Cu" signal "L03-Inner Layer")
		(2 "B.Cu" signal "L04-Bottom Layer")
		(9 "F.Adhes" user "F.Adhesive")
		(11 "B.Adhes" user "B.Adhesive")
		(13 "F.Paste" user "Top Paste")
		(15 "B.Paste" user "Bottom Paste")
		(5 "F.SilkS" user "Top Overlay")
		(7 "B.SilkS" user "Bottom Overlay")
		(1 "F.Mask" user "Top Solder")
		(3 "B.Mask" user "Bottom Solder")
		(17 "Dwgs.User" user "User.Drawings")
		(19 "Cmts.User" user "User.Comments")
		(21 "Eco1.User" user "User.Eco1")
		(23 "Eco2.User" user "User.Eco2")
		(25 "Edge.Cuts" user)
		(27 "Margin" user)
		(31 "F.CrtYd" user "Top Courtyard")
		(29 "B.CrtYd" user "Bottom Courtyard")
		(35 "F.Fab" user "Top Component Outline")
		(33 "B.Fab" user "Bottom Component Outline 2")
	)
	(footprint "FAB_SA45_DaughterCard:Microchip_SA45"
		(locked yes)
		(layer "F.Cu")
		(at 149.501105 105.003605 180)
		(property "Reference" "U1"
			(at 21.025 16.58071 0)
			(unlocked yes)
			(layer "F.SilkS")
			(effects
				(font
					(face "Arial")
					(size 0.63 0.63)
					(thickness 0.254)
				)
			)
		)
		(property "Value" "Microchip_SA45"
			(at 7.280385 -22.215602 0)
			(unlocked yes)
			(layer "F.SilkS")
			(hide yes)
			(effects
				(font
					(size 1.524 1.524)
					(thickness 0.254)
				)
			)
		)
		(sheetname "SCH_SA45_DaughterCard")
		(sheetfile "SCH_SA45_DaughterCard.kicad_sch")
		(duplicate_pad_numbers_are_jumpers no)
		(fp_line
			(start 20.6 17.9)
			(end -20.6 17.9)
			(stroke
				(width 0.1)
				(type solid)
			)
			(layer "F.CrtYd")
		)
		(fp_line
			(start 20.6 -17.9)
			(end 20.6 17.9)
			(stroke
				(width 0.1)
				(type solid)
			)
			(layer "F.CrtYd")
		)
		(fp_line
			(start 20.6 -17.9)
			(end -20.6 -17.9)
			(stroke
				(width 0.1)
				(type solid)
			)
			(layer "F.CrtYd")
		)
		(fp_line
			(start -20.6 -17.9)
			(end -20.6 17.9)
			(stroke
				(width 0.1)
				(type solid)
			)
			(layer "F.CrtYd")
		)
		(fp_text user ""
			(at 1.117795 -0.44646 180)
			(unlocked yes)
			(layer "F.Fab")
			(effects
				(font
					(face "Arial")
					(size 0.63 0.63)
					(thickness 0.254)
				)
			)
		)
		(fp_text user "${REFERENCE}"
			(at -0.0127 -0.11801 180)
			(unlocked yes)
			(layer "F.Fab")
			(effects
				(font
					(face "Arial")
					(size 0.63 0.63)
					(thickness 0.254)
				)
			)
		)
		(pad "1" thru_hole circle
			(at 16.51 12.7 270)
			(size 1.524 1.524)
			(drill 0.762)
			(layers "*.Cu" "*.Mask")
			(remove_unused_layers no)
			(thermal_bridge_angle 90)
		)
		(pad "4" thru_hole circle
			(at 16.51 -2.54 270)
			(size 1.524 1.524)
			(drill 0.762)
			(layers "*.Cu" "*.Mask")
			(remove_unused_layers no)
			(thermal_bridge_angle 90)
		)
		(pad "5" thru_hole circle
			(at 16.51 -7.62 270)
			(size 1.524 1.524)
			(drill 0.762)
			(layers "*.Cu" "*.Mask")
			(remove_unused_layers no)
			(net "TX")
			(thermal_bridge_angle 90)
		)
		(pad "6" thru_hole circle
			(at 16.51 -12.7 270)
			(size 1.524 1.524)
			(drill 0.762)
			(layers "*.Cu" "*.Mask")
			(remove_unused_layers no)
			(net "RX")
			(thermal_bridge_angle 90)
		)
		(pad "7" thru_hole circle
			(at -16.51 -12.7 270)
			(size 1.562 1.562)
			(drill 0.962)
			(layers "*.Cu" "*.Mask")
			(remove_unused_layers no)
			(net "+3.3V_OSC")
			(thermal_bridge_angle 90)
		)
		(pad "8" thru_hole circle
			(at -16.51 -7.62 270)
			(size 1.562 1.562)
			(drill 0.962)
			(layers "*.Cu" "*.Mask")
			(remove_unused_layers no)
			(net "GND")
			(thermal_bridge_angle 90)
		)
		(pad "9" thru_hole circle
			(at -16.51 -2.54 270)
			(size 1.562 1.562)
			(drill 0.962)
			(layers "*.Cu" "*.Mask")
			(remove_unused_layers no)
			(net "1PPS_IN")
			(thermal_bridge_angle 90)
		)
		(pad "10" thru_hole circle
			(at -16.51 2.54 270)
			(size 1.562 1.562)
			(drill 0.962)
			(layers "*.Cu" "*.Mask")
			(remove_unused_layers no)
			(net "1PPS_OUT")
			(thermal_bridge_angle 90)
		)
		(pad "12" thru_hole circle
			(at -16.51 12.7 180)
			(size 1.562 1.562)
			(drill 0.962)
			(layers "*.Cu" "*.Mask")
			(remove_unused_layers no)
			(net "RF_OUTPUT")
			(thermal_bridge_angle 90)
		)
	)
	(footprint "Vault:FID_1p0mm"
		(layer "F.Cu")
		(at 171.286105 81.818605)
		(property "Reference" "Designator3"
			(at 7.084135 -3.019298 0)
			(unlocked yes)
			(layer "F.SilkS")
			(hide yes)
			(effects
				(font
					(size 1.524 1.524)
					(thickness 0.254)
				)
			)
		)
		(property "Value" "Comment"
			(at 5.07844 -0.707898 0)
			(unlocked yes)
			(layer "F.SilkS")
			(hide yes)
			(effects
				(font
					(size 1.524 1.524)
					(thickness 0.254)
				)
			)
		)
		(sheetfile ".kicad_sch")
		(duplicate_pad_numbers_are_jumpers no)
		(fp_circle
			(center 0 0)
			(end 0 -1)
			(stroke
				(width 0.1)
				(type solid)
			)
			(fill no)
			(layer "F.CrtYd")
		)
		(pad "1" smd circle
			(at 0 0 90)
			(size 1 1)
			(layers "F.Cu" "F.Mask" "F.Paste")
			(solder_mask_margin 0.5)
			(solder_paste_margin -6)
			(thermal_bridge_angle 90)
		)
		(zone
			(layer "F.Cu")
			(hatch edge 0.5)
			(connect_pads
				(clearance 0)
			)
			(min_thickness 0.25)
			(keepout
				(tracks not_allowed)
				(vias not_allowed)
				(pads allowed)
				(copperpour not_allowed)
				(footprints allowed)
			)
			(placement
				(enabled no)
				(sheetname "")
			)
			(fill
				(thermal_gap 0.5)
				(thermal_bridge_width 0.5)
				(island_removal_mode 0)
			)
			(polygon
				(pts
					(xy 171.57639 80.861665) (xy 171.757502 80.936684) (xy 171.920498 81.045595) (xy 172.059115 81.184212)
					(xy 172.168026 81.347208) (xy 172.243045 81.52832) (xy 172.28129 81.720588) (xy 172.28129 81.916622)
					(xy 172.243045 82.10889) (xy 172.168026 82.290002) (xy 172.059115 82.452998) (xy 171.920498 82.591615)
					(xy 171.757502 82.700526) (xy 171.57639 82.775545) (xy 171.384122 82.81379) (xy 171.188088 82.81379)
					(xy 170.99582 82.775545) (xy 170.814708 82.700526) (xy 170.651712 82.591615) (xy 170.513095 82.452998)
					(xy 170.404184 82.290002) (xy 170.329165 82.10889) (xy 170.29092 81.916622) (xy 170.29092 81.752779)
					(xy 170.786105 81.752779) (xy 170.786105 81.884431) (xy 170.82018 82.011598) (xy 170.886006 82.125612)
					(xy 170.979098 82.218704) (xy 171.093112 82.28453) (xy 171.220279 82.318605) (xy 171.351931 82.318605)
					(xy 171.479098 82.28453) (xy 171.593112 82.218704) (xy 171.686204 82.125612) (xy 171.75203 82.011598)
					(xy 171.786105 81.884431) (xy 171.786105 81.752779) (xy 171.75203 81.625612) (xy 171.686204 81.511598)
					(xy 171.593112 81.418506) (xy 171.479098 81.35268) (xy 171.351931 81.318605) (xy 171.220279 81.318605)
					(xy 171.093112 81.35268) (xy 170.979098 81.418506) (xy 170.886006 81.511598) (xy 170.82018 81.625612)
					(xy 170.786105 81.752779) (xy 170.29092 81.752779) (xy 170.29092 81.720588) (xy 170.329165 81.52832)
					(xy 170.404184 81.347208) (xy 170.513095 81.184212) (xy 170.651712 81.045595) (xy 170.814708 80.936684)
					(xy 170.99582 80.861665) (xy 171.188088 80.82342) (xy 171.384122 80.82342)
				)
			)
		)
	)
	(footprint "Vault:FID_1p0mm"
		(layer "F.Cu")
		(at 125.786105 81.818605)
		(property "Reference" "Designator1"
			(at 7.084135 -3.019298 0)
			(unlocked yes)
			(layer "F.SilkS")
			(hide yes)
			(effects
				(font
					(size 1.524 1.524)
					(thickness 0.254)
				)
			)
		)
		(property "Value" "Comment"
			(at 5.07844 -0.707898 0)
			(unlocked yes)
			(layer "F.SilkS")
			(hide yes)
			(effects
				(font
					(size 1.524 1.524)
					(thickness 0.254)
				)
			)
		)
		(sheetfile ".kicad_sch")
		(duplicate_pad_numbers_are_jumpers no)
		(fp_circle
			(center 0 0)
			(end 0 -1)
			(stroke
				(width 0.1)
				(type solid)
			)
			(fill no)
			(layer "F.CrtYd")
		)
		(pad "1" smd circle
			(at 0 0 90)
			(size 1 1)
			(layers "F.Cu" "F.Mask" "F.Paste")
			(solder_mask_margin 0.5)
			(solder_paste_margin -6)
			(thermal_bridge_angle 90)
		)
		(zone
			(layer "F.Cu")
			(hatch edge 0.5)
			(connect_pads
				(clearance 0)
			)
			(min_thickness 0.25)
			(keepout
				(tracks not_allowed)
				(vias not_allowed)
				(pads allowed)
				(copperpour not_allowed)
				(footprints allowed)
			)
			(placement
				(enabled no)
				(sheetname "")
			)
			(fill
				(thermal_gap 0.5)
				(thermal_bridge_width 0.5)
				(island_removal_mode 0)
			)
			(polygon
				(pts
					(xy 126.07639 80.861665) (xy 126.257502 80.936684) (xy 126.420498 81.045595) (xy 126.559115 81.184212)
					(xy 126.668026 81.347208) (xy 126.743045 81.52832) (xy 126.78129 81.720588) (xy 126.78129 81.916622)
					(xy 126.743045 82.10889) (xy 126.668026 82.290002) (xy 126.559115 82.452998) (xy 126.420498 82.591615)
					(xy 126.257502 82.700526) (xy 126.07639 82.775545) (xy 125.884122 82.81379) (xy 125.688088 82.81379)
					(xy 125.49582 82.775545) (xy 125.314708 82.700526) (xy 125.151712 82.591615) (xy 125.013095 82.452998)
					(xy 124.904184 82.290002) (xy 124.829165 82.10889) (xy 124.79092 81.916622) (xy 124.79092 81.752779)
					(xy 125.286105 81.752779) (xy 125.286105 81.884431) (xy 125.32018 82.011598) (xy 125.386006 82.125612)
					(xy 125.479098 82.218704) (xy 125.593112 82.28453) (xy 125.720279 82.318605) (xy 125.851931 82.318605)
					(xy 125.979098 82.28453) (xy 126.093112 82.218704) (xy 126.186204 82.125612) (xy 126.25203 82.011598)
					(xy 126.286105 81.884431) (xy 126.286105 81.752779) (xy 126.25203 81.625612) (xy 126.186204 81.511598)
					(xy 126.093112 81.418506) (xy 125.979098 81.35268) (xy 125.851931 81.318605) (xy 125.720279 81.318605)
					(xy 125.593112 81.35268) (xy 125.479098 81.418506) (xy 125.386006 81.511598) (xy 125.32018 81.625612)
					(xy 125.286105 81.752779) (xy 124.79092 81.752779) (xy 124.79092 81.720588) (xy 124.829165 81.52832)
					(xy 124.904184 81.347208) (xy 125.013095 81.184212) (xy 125.151712 81.045595) (xy 125.314708 80.936684)
					(xy 125.49582 80.861665) (xy 125.688088 80.82342) (xy 125.884122 80.82342)
				)
			)
		)
	)
	(footprint "FAB_SA45_DaughterCard:IQD_ICPT-1"
		(locked yes)
		(layer "F.Cu")
		(at 149.501105 105.003605 180)
		(property "Reference" "U2"
			(at 23.35 17.75571 0)
			(unlocked yes)
			(layer "F.SilkS")
			(effects
				(font
					(face "Arial")
					(size 0.63 0.63)
					(thickness 0.254)
				)
			)
		)
		(property "Value" "IQD_ICPT-1"
			(at 43.90612 -29.403802 0)
			(unlocked yes)
			(layer "F.SilkS")
			(hide yes)
			(effects
				(font
					(size 1.524 1.524)
					(thickness 0.254)
				)
			)
		)
		(sheetname "SCH_SA45_DaughterCard")
		(sheetfile "SCH_SA45_DaughterCard.kicad_sch")
		(duplicate_pad_numbers_are_jumpers no)
		(fp_line
			(start 22.7 18.2)
			(end -22.7 18.2)
			(stroke
				(width 0.1)
				(type solid)
			)
			(layer "F.CrtYd")
		)
		(fp_line
			(start 22.7 -18.2)
			(end 22.7 18.2)
			(stroke
				(width 0.1)
				(type solid)
			)
			(layer "F.CrtYd")
		)
		(fp_line
			(start 22.7 -18.2)
			(end -11.8 -18.2)
			(stroke
				(width 0.1)
				(type solid)
			)
			(layer "F.CrtYd")
		)
		(fp_line
			(start -11.8 -18.2)
			(end -22.7 -18.2)
			(stroke
				(width 0.1)
				(type solid)
			)
			(layer "F.CrtYd")
		)
		(fp_line
			(start -22.7 -18.2)
			(end -22.7 18.2)
			(stroke
				(width 0.1)
				(type solid)
			)
			(layer "F.CrtYd")
		)
		(fp_text user ""
			(at 1.117795 -0.44646 180)
			(unlocked yes)
			(layer "F.Fab")
			(effects
				(font
					(face "Arial")
					(size 0.63 0.63)
					(thickness 0.254)
				)
			)
		)
		(fp_text user "${REFERENCE}"
			(at -0.0127 -0.11801 180)
			(unlocked yes)
			(layer "F.Fab")
			(effects
				(font
					(face "Arial")
					(size 0.63 0.63)
					(thickness 0.254)
				)
			)
		)
		(pad "1" thru_hole circle
			(at 16.51 12.7 270)
			(size 1.8 1.8)
			(drill 1.2)
			(layers "*.Cu" "*.Mask")
			(remove_unused_layers no)
			(thermal_bridge_angle 90)
		)
		(pad "2" thru_hole circle
			(at 16.51 -2.54 270)
			(size 1.8 1.8)
			(drill 1.2)
			(layers "*.Cu" "*.Mask")
			(remove_unused_layers no)
			(thermal_bridge_angle 90)
		)
		(pad "3" thru_hole circle
			(at 16.51 -7.62 270)
			(size 1.8 1.8)
			(drill 1.2)
			(layers "*.Cu" "*.Mask")
			(remove_unused_layers no)
			(net "TX")
			(thermal_bridge_angle 90)
		)
		(pad "4" thru_hole circle
			(at 16.51 -12.7 270)
			(size 1.8 1.8)
			(drill 1.2)
			(layers "*.Cu" "*.Mask")
			(remove_unused_layers no)
			(net "RX")
			(thermal_bridge_angle 90)
		)
		(pad "5" thru_hole circle
			(at -16.51 -12.7 270)
			(size 1.8 1.8)
			(drill 1.2)
			(layers "*.Cu" "*.Mask")
			(remove_unused_layers no)
			(net "+3.3V_OSC")
			(thermal_bridge_angle 90)
		)
		(pad "6" thru_hole circle
			(at -16.51 -7.62 270)
			(size 1.8 1.8)
			(drill 1.2)
			(layers "*.Cu" "*.Mask")
			(remove_unused_layers no)
			(net "GND")
			(thermal_bridge_angle 90)
		)
		(pad "7" thru_hole circle
			(at -16.51 -2.54 270)
			(size 1.8 1.8)
			(drill 1.2)
			(layers "*.Cu" "*.Mask")
			(remove_unused_layers no)
			(net "1PPS_IN")
			(thermal_bridge_angle 90)
		)
		(pad "8" thru_hole circle
			(at -16.51 2.54 270)
			(size 1.8 1.8)
			(drill 1.2)
			(layers "*.Cu" "*.Mask")
			(remove_unused_layers no)
			(net "1PPS_OUT")
			(thermal_bridge_angle 90)
		)
		(pad "9" thru_hole circle
			(at -16.51 12.7 180)
			(size 1.8 1.8)
			(drill 1.2)
			(layers "*.Cu" "*.Mask")
			(remove_unused_layers no)
			(net "RF_OUTPUT")
			(thermal_bridge_angle 90)
		)
		(zone
			(layer "F.Cu")
			(hatch edge 0.5)
			(connect_pads
				(clearance 0)
			)
			(min_thickness 0.25)
			(keepout
				(tracks not_allowed)
				(vias not_allowed)
				(pads not_allowed)
				(copperpour not_allowed)
				(footprints allowed)
			)
			(placement
				(enabled no)
				(sheetname "")
			)
			(fill
				(thermal_gap 0.5)
				(thermal_bridge_width 0.5)
				(island_removal_mode 0)
			)
			(polygon
				(pts
					(xy 172.001105 123.003605) (xy 172.001105 87.003605) (xy 127.001105 87.003605) (xy 127.001105 123.003605)
				)
			)
		)
	)
	(footprint "Vault:FID_1p0mm"
		(layer "F.Cu")
		(at 125.961105 128.043605)
		(property "Reference" "Designator2"
			(at 7.084135 -3.019298 0)
			(unlocked yes)
			(layer "F.SilkS")
			(hide yes)
			(effects
				(font
					(size 1.524 1.524)
					(thickness 0.254)
				)
			)
		)
		(property "Value" "Comment"
			(at 5.07844 -0.707898 0)
			(unlocked yes)
			(layer "F.SilkS")
			(hide yes)
			(effects
				(font
					(size 1.524 1.524)
					(thickness 0.254)
				)
			)
		)
		(sheetfile ".kicad_sch")
		(duplicate_pad_numbers_are_jumpers no)
		(fp_circle
			(center 0 0)
			(end 0 -1)
			(stroke
				(width 0.1)
				(type solid)
			)
			(fill no)
			(layer "F.CrtYd")
		)
		(pad "1" smd circle
			(at 0 0 90)
			(size 1 1)
			(layers "F.Cu" "F.Mask" "F.Paste")
			(solder_mask_margin 0.5)
			(solder_paste_margin -6)
			(thermal_bridge_angle 90)
		)
		(zone
			(layer "F.Cu")
			(hatch edge 0.5)
			(connect_pads
				(clearance 0)
			)
			(min_thickness 0.25)
			(keepout
				(tracks not_allowed)
				(vias not_allowed)
				(pads allowed)
				(copperpour not_allowed)
				(footprints allowed)
			)
			(placement
				(enabled no)
				(sheetname "")
			)
			(fill
				(thermal_gap 0.5)
				(thermal_bridge_width 0.5)
				(island_removal_mode 0)
			)
			(polygon
				(pts
					(xy 126.25139 127.086665) (xy 126.432502 127.161684) (xy 126.595498 127.270595) (xy 126.734115 127.409212)
					(xy 126.843026 127.572208) (xy 126.918045 127.75332) (xy 126.95629 127.945588) (xy 126.95629 128.141622)
					(xy 126.918045 128.33389) (xy 126.843026 128.515002) (xy 126.734115 128.677998) (xy 126.595498 128.816615)
					(xy 126.432502 128.925526) (xy 126.25139 129.000545) (xy 126.059122 129.03879) (xy 125.863088 129.03879)
					(xy 125.67082 129.000545) (xy 125.489708 128.925526) (xy 125.326712 128.816615) (xy 125.188095 128.677998)
					(xy 125.079184 128.515002) (xy 125.004165 128.33389) (xy 124.96592 128.141622) (xy 124.96592 127.977779)
					(xy 125.461105 127.977779) (xy 125.461105 128.109431) (xy 125.49518 128.236598) (xy 125.561006 128.350612)
					(xy 125.654098 128.443704) (xy 125.768112 128.50953) (xy 125.895279 128.543605) (xy 126.026931 128.543605)
					(xy 126.154098 128.50953) (xy 126.268112 128.443704) (xy 126.361204 128.350612) (xy 126.42703 128.236598)
					(xy 126.461105 128.109431) (xy 126.461105 127.977779) (xy 126.42703 127.850612) (xy 126.361204 127.736598)
					(xy 126.268112 127.643506) (xy 126.154098 127.57768) (xy 126.026931 127.543605) (xy 125.895279 127.543605)
					(xy 125.768112 127.57768) (xy 125.654098 127.643506) (xy 125.561006 127.736598) (xy 125.49518 127.850612)
					(xy 125.461105 127.977779) (xy 124.96592 127.977779) (xy 124.96592 127.945588) (xy 125.004165 127.75332)
					(xy 125.079184 127.572208) (xy 125.188095 127.409212) (xy 125.326712 127.270595) (xy 125.489708 127.161684)
					(xy 125.67082 127.086665) (xy 125.863088 127.04842) (xy 126.059122 127.04842)
				)
			)
		)
	)
	(footprint "Vault:TH001V_109DIA_000mt_8600-0"
		(layer "B.Cu")
		(at 142.431105 81.993605 180)
		(property "Reference" "P10"
			(at 0 -1.90429 0)
			(unlocked yes)
			(layer "B.SilkS")
			(effects
				(font
					(face "Arial")
					(size 0.63 0.63)
					(thickness 0.254)
				)
				(justify mirror)
			)
		)
		(property "Value" "Mill-Max_8600-0-05-80-00-00-03-0"
			(at 22.534825 -2.89778 0)
			(unlocked yes)
			(layer "B.SilkS")
			(hide yes)
			(effects
				(font
					(face "Arial")
					(size 0.63 0.63)
					(thickness 0.254)
				)
				(justify mirror)
			)
		)
		(sheetname "SCH_SA45_DaughterCard")
		(sheetfile "SCH_SA45_DaughterCard.kicad_sch")
		(duplicate_pad_numbers_are_jumpers no)
		(fp_line
			(start 1.4 1.4)
			(end -1.4 1.4)
			(stroke
				(width 0.1)
				(type solid)
			)
			(layer "B.CrtYd")
		)
		(fp_line
			(start 1.4 -1.4)
			(end 1.4 1.4)
			(stroke
				(width 0.1)
				(type solid)
			)
			(layer "B.CrtYd")
		)
		(fp_line
			(start 1.4 -1.4)
			(end -1.4 -1.4)
			(stroke
				(width 0.1)
				(type solid)
			)
			(layer "B.CrtYd")
		)
		(fp_line
			(start -1.4 -1.4)
			(end -1.4 1.4)
			(stroke
				(width 0.1)
				(type solid)
			)
			(layer "B.CrtYd")
		)
		(fp_circle
			(center 0 0)
			(end 0 0.545)
			(stroke
				(width 0.1)
				(type solid)
			)
			(fill no)
			(layer "B.Fab")
		)
		(fp_text user "${REFERENCE}"
			(at 0.000005 0.166251 360)
			(unlocked yes)
			(layer "B.Fab")
			(effects
				(font
					(face "Arial")
					(size 0.8001 0.8001)
					(thickness 0.254)
				)
				(justify mirror)
			)
		)
		(pad "1" thru_hole circle
			(at 0 -0.02 180)
			(size 2.09 2.09)
			(drill 1.09)
			(layers "*.Cu" "*.Mask")
			(remove_unused_layers no)
			(net "1PPS_OUT")
			(solder_mask_margin 0.05)
			(solder_paste_margin -2147.48364)
			(thermal_bridge_angle 90)
		)
	)
)
